(kicad_pcb
	(version 20260206)
	(generator "pcbnew")
	(generator_version "10.0")
	(general
		(thickness 1.6)
		(legacy_teardrops no)
	)
	(paper "A4")
	(title_block
		(title "01162023_DA0F0TEBIF0_F0T_Expander_BD_F_brd_V02_OCP.brd")
		(comment 1 "Grand Teton / footprints 8118-8126 of 9728")
	)
	(layers
		(0 "F.Cu" signal "TOP")
		(4 "In1.Cu" signal "GND")
		(6 "In2.Cu" signal "VCC")
		(8 "In3.Cu" signal "VCC1")
		(10 "In4.Cu" signal "GND1")
		(12 "In5.Cu" signal "IN1")
		(14 "In6.Cu" signal "GND2")
		(16 "In7.Cu" signal "IN2")
		(18 "In8.Cu" signal "GND3")
		(20 "In9.Cu" signal "IN3")
		(22 "In10.Cu" signal "GND4")
		(24 "In11.Cu" signal "IN4")
		(26 "In12.Cu" signal "GND5")
		(28 "In13.Cu" signal "IN5")
		(30 "In14.Cu" signal "GND6")
		(32 "In15.Cu" signal "IN6")
		(34 "In16.Cu" signal "GND7")
		(2 "B.Cu" signal "BOTTOM")
		(9 "F.Adhes" user "F.Adhesive")
		(11 "B.Adhes" user "B.Adhesive")
		(13 "F.Paste" user "Package Geometry/Pastemask Top")
		(15 "B.Paste" user "Package Geometry/Pastemask Bottom")
		(5 "F.SilkS" user "Ref Des/Silkscreen Top")
		(7 "B.SilkS" user "Ref Des/Silkscreen Bottom")
		(1 "F.Mask" user "Board Geometry/Soldermask Top")
		(3 "B.Mask" user "Board Geometry/Soldermask Bottom")
		(17 "Dwgs.User" user "User.Drawings")
		(19 "Cmts.User" user "User.Comments")
		(21 "Eco1.User" user "User.Eco1")
		(23 "Eco2.User" user "User.Eco2")
		(25 "Edge.Cuts" user "Board Geometry/Outline")
		(27 "Margin" user)
		(31 "F.CrtYd" user "Package Geometry/Place Bound Top")
		(29 "B.CrtYd" user "Package Geometry/Place Bound Bottom")
		(35 "F.Fab" user "Ref Des/Assembly Top")
		(33 "B.Fab" user "Ref Des/Assembly Bottom")
	)
	(footprint ""
		(layer "B.Cu")
		(at 361.437936 -281.024838 90)
		(property "Reference" "PC192"
			(at 0 0 90)
			(layer "B.SilkS")
			(hide yes)
			(effects
				(font
					(size 1.27 1.27)
				)
				(justify mirror)
			)
		)
		(property "Value" ""
			(at 0 0 90)
			(layer "B.Fab")
			(effects
				(font
					(size 1.27 1.27)
				)
				(justify mirror)
			)
		)
		(duplicate_pad_numbers_are_jumpers no)
		(fp_line
			(start 1.524 -0.762)
			(end -1.524 -0.762)
			(stroke
				(width 0.1524)
				(type default)
			)
			(layer "B.SilkS")
		)
		(fp_line
			(start -1.524 -0.762)
			(end -1.524 0.762)
			(stroke
				(width 0.1524)
				(type default)
			)
			(layer "B.SilkS")
		)
		(fp_line
			(start 1.524 0.762)
			(end 1.524 -0.762)
			(stroke
				(width 0.1524)
				(type default)
			)
			(layer "B.SilkS")
		)
		(fp_line
			(start -1.524 0.762)
			(end 1.524 0.762)
			(stroke
				(width 0.1524)
				(type default)
			)
			(layer "B.SilkS")
		)
		(fp_line
			(start 1.1049 -0.724916)
			(end 1.1049 0.724916)
			(stroke
				(width 0.1)
				(type default)
			)
			(layer "B.Fab")
		)
		(fp_line
			(start -1.1049 -0.724916)
			(end 1.1049 -0.724916)
			(stroke
				(width 0.1)
				(type default)
			)
			(layer "B.Fab")
		)
		(fp_line
			(start 1.1049 0.724916)
			(end -1.1049 0.724916)
			(stroke
				(width 0.1)
				(type default)
			)
			(layer "B.Fab")
		)
		(fp_line
			(start -1.1049 0.724916)
			(end -1.1049 -0.724916)
			(stroke
				(width 0.1)
				(type default)
			)
			(layer "B.Fab")
		)
		(pad "1" smd rect
			(at 0.889 0 90)
			(size 1.016 1.27)
			(layers "B.Cu" "B.Mask" "B.Paste")
			(net "SW_P12V_P0V8_PEX3_FLT")
		)
		(pad "2" smd rect
			(at -0.889 0 90)
			(size 1.016 1.27)
			(layers "B.Cu" "B.Mask" "B.Paste")
			(net "GND")
		)
	)
	(footprint ""
		(layer "B.Cu")
		(at 417.450016 -294.4749 180)
		(property "Reference" "C1927"
			(at 0 0 0)
			(layer "B.SilkS")
			(hide yes)
			(effects
				(font
					(size 1.27 1.27)
				)
				(justify mirror)
			)
		)
		(property "Value" ""
			(at 0 0 0)
			(layer "B.Fab")
			(effects
				(font
					(size 1.27 1.27)
				)
				(justify mirror)
			)
		)
		(duplicate_pad_numbers_are_jumpers no)
		(fp_line
			(start 0.299974 0.150114)
			(end 0.299974 -0.150114)
			(stroke
				(width 0.1)
				(type default)
			)
			(layer "B.Fab")
		)
		(fp_line
			(start 0.299974 -0.150114)
			(end -0.299974 -0.150114)
			(stroke
				(width 0.1)
				(type default)
			)
			(layer "B.Fab")
		)
		(fp_line
			(start -0.299974 0.150114)
			(end 0.299974 0.150114)
			(stroke
				(width 0.1)
				(type default)
			)
			(layer "B.Fab")
		)
		(fp_line
			(start -0.299974 -0.150114)
			(end -0.299974 0.150114)
			(stroke
				(width 0.1)
				(type default)
			)
			(layer "B.Fab")
		)
		(pad "1" smd rect
			(at 0.2667 0)
			(size 0.3048 0.381)
			(layers "B.Cu" "B.Mask" "B.Paste")
			(net "P0V8_SERDES_VDDA_PEX3")
		)
		(pad "2" smd rect
			(at -0.2667 0)
			(size 0.3048 0.381)
			(layers "B.Cu" "B.Mask" "B.Paste")
			(net "GND")
		)
	)
	(footprint ""
		(layer "B.Cu")
		(at 340.374224 -308.747668 90)
		(property "Reference" "C4320"
			(at 0 0 90)
			(layer "B.SilkS")
			(hide yes)
			(effects
				(font
					(size 1.27 1.27)
				)
				(justify mirror)
			)
		)
		(property "Value" ""
			(at 0 0 90)
			(layer "B.Fab")
			(effects
				(font
					(size 1.27 1.27)
				)
				(justify mirror)
			)
		)
		(duplicate_pad_numbers_are_jumpers no)
		(fp_line
			(start 0.299974 -0.150114)
			(end -0.299974 -0.150114)
			(stroke
				(width 0.1)
				(type default)
			)
			(layer "B.Fab")
		)
		(fp_line
			(start -0.299974 -0.150114)
			(end -0.299974 0.150114)
			(stroke
				(width 0.1)
				(type default)
			)
			(layer "B.Fab")
		)
		(fp_line
			(start 0.299974 0.150114)
			(end 0.299974 -0.150114)
			(stroke
				(width 0.1)
				(type default)
			)
			(layer "B.Fab")
		)
		(fp_line
			(start -0.299974 0.150114)
			(end 0.299974 0.150114)
			(stroke
				(width 0.1)
				(type default)
			)
			(layer "B.Fab")
		)
		(pad "1" smd rect
			(at 0.2667 0 270)
			(size 0.3048 0.381)
			(layers "B.Cu" "B.Mask" "B.Paste")
			(net "P0V8_PEX2")
		)
		(pad "2" smd rect
			(at -0.2667 0 270)
			(size 0.3048 0.381)
			(layers "B.Cu" "B.Mask" "B.Paste")
			(net "GND")
		)
	)
	(footprint ""
		(layer "B.Cu")
		(at 99.506278 -350.3803 90)
		(property "Reference" "C4181"
			(at 0 0 90)
			(layer "B.SilkS")
			(hide yes)
			(effects
				(font
					(size 1.27 1.27)
				)
				(justify mirror)
			)
		)
		(property "Value" ""
			(at 0 0 90)
			(layer "B.Fab")
			(effects
				(font
					(size 1.27 1.27)
				)
				(justify mirror)
			)
		)
		(duplicate_pad_numbers_are_jumpers no)
		(fp_line
			(start 0.7874 -0.4064)
			(end -0.7874 -0.4064)
			(stroke
				(width 0.1524)
				(type default)
			)
			(layer "B.SilkS")
		)
		(fp_line
			(start -0.7874 -0.4064)
			(end -0.7874 0.4064)
			(stroke
				(width 0.1524)
				(type default)
			)
			(layer "B.SilkS")
		)
		(fp_line
			(start 0.7874 0.4064)
			(end 0.7874 -0.4064)
			(stroke
				(width 0.1524)
				(type default)
			)
			(layer "B.SilkS")
		)
		(fp_line
			(start -0.7874 0.4064)
			(end 0.7874 0.4064)
			(stroke
				(width 0.1524)
				(type default)
			)
			(layer "B.SilkS")
		)
		(fp_line
			(start 0.67945 -0.305054)
			(end 0.12065 -0.305054)
			(stroke
				(width 0.1)
				(type default)
			)
			(layer "B.Fab")
		)
		(fp_line
			(start 0.12065 -0.305054)
			(end 0.12065 -0.2794)
			(stroke
				(width 0.1)
				(type default)
			)
			(layer "B.Fab")
		)
		(fp_line
			(start -0.12065 -0.3048)
			(end -0.67945 -0.3048)
			(stroke
				(width 0.1)
				(type default)
			)
			(layer "B.Fab")
		)
		(fp_line
			(start -0.67945 -0.3048)
			(end -0.67945 0.3048)
			(stroke
				(width 0.1)
				(type default)
			)
			(layer "B.Fab")
		)
		(fp_line
			(start 0.12065 -0.2794)
			(end -0.12065 -0.2794)
			(stroke
				(width 0.1)
				(type default)
			)
			(layer "B.Fab")
		)
		(fp_line
			(start -0.12065 -0.2794)
			(end -0.12065 -0.3048)
			(stroke
				(width 0.1)
				(type default)
			)
			(layer "B.Fab")
		)
		(fp_line
			(start 0.12065 0.2794)
			(end 0.12065 0.3048)
			(stroke
				(width 0.1)
				(type default)
			)
			(layer "B.Fab")
		)
		(fp_line
			(start -0.120396 0.2794)
			(end 0.12065 0.2794)
			(stroke
				(width 0.1)
				(type default)
			)
			(layer "B.Fab")
		)
		(fp_line
			(start 0.67945 0.3048)
			(end 0.67945 -0.305054)
			(stroke
				(width 0.1)
				(type default)
			)
			(layer "B.Fab")
		)
		(fp_line
			(start 0.12065 0.3048)
			(end 0.67945 0.3048)
			(stroke
				(width 0.1)
				(type default)
			)
			(layer "B.Fab")
		)
		(fp_line
			(start -0.120396 0.3048)
			(end -0.120396 0.2794)
			(stroke
				(width 0.1)
				(type default)
			)
			(layer "B.Fab")
		)
		(fp_line
			(start -0.67945 0.3048)
			(end -0.120396 0.3048)
			(stroke
				(width 0.1)
				(type default)
			)
			(layer "B.Fab")
		)
		(pad "1" smd circle
			(at 0.40005 0 270)
			(size 0 0)
			(layers "B.Cu" "B.Mask" "B.Paste")
			(net "P3V3_CLK_BUFFER_9ZXL0451E_S3_VZX3P3")
		)
		(pad "2" smd circle
			(at -0.40005 0 270)
			(size 0 0)
			(layers "B.Cu" "B.Mask" "B.Paste")
			(net "GND")
		)
	)
	(footprint ""
		(layer "B.Cu")
		(at 105.380536 -391.470134)
		(property "Reference" "C3628"
			(at 0 0 0)
			(layer "B.SilkS")
			(hide yes)
			(effects
				(font
					(size 1.27 1.27)
				)
				(justify mirror)
			)
		)
		(property "Value" ""
			(at 0 0 0)
			(layer "B.Fab")
			(effects
				(font
					(size 1.27 1.27)
				)
				(justify mirror)
			)
		)
		(duplicate_pad_numbers_are_jumpers no)
		(fp_line
			(start -0.7874 -0.4064)
			(end -0.7874 0.4064)
			(stroke
				(width 0.1524)
				(type default)
			)
			(layer "B.SilkS")
		)
		(fp_line
			(start -0.7874 0.4064)
			(end 0.7874 0.4064)
			(stroke
				(width 0.1524)
				(type default)
			)
			(layer "B.SilkS")
		)
		(fp_line
			(start 0.7874 -0.4064)
			(end -0.7874 -0.4064)
			(stroke
				(width 0.1524)
				(type default)
			)
			(layer "B.SilkS")
		)
		(fp_line
			(start 0.7874 0.4064)
			(end 0.7874 -0.4064)
			(stroke
				(width 0.1524)
				(type default)
			)
			(layer "B.SilkS")
		)
		(fp_line
			(start -0.67945 -0.3048)
			(end -0.67945 0.3048)
			(stroke
				(width 0.1)
				(type default)
			)
			(layer "B.Fab")
		)
		(fp_line
			(start -0.67945 0.3048)
			(end -0.120396 0.3048)
			(stroke
				(width 0.1)
				(type default)
			)
			(layer "B.Fab")
		)
		(fp_line
			(start -0.12065 -0.3048)
			(end -0.67945 -0.3048)
			(stroke
				(width 0.1)
				(type default)
			)
			(layer "B.Fab")
		)
		(fp_line
			(start -0.12065 -0.2794)
			(end -0.12065 -0.3048)
			(stroke
				(width 0.1)
				(type default)
			)
			(layer "B.Fab")
		)
		(fp_line
			(start -0.120396 0.2794)
			(end 0.12065 0.2794)
			(stroke
				(width 0.1)
				(type default)
			)
			(layer "B.Fab")
		)
		(fp_line
			(start -0.120396 0.3048)
			(end -0.120396 0.2794)
			(stroke
				(width 0.1)
				(type default)
			)
			(layer "B.Fab")
		)
		(fp_line
			(start 0.12065 -0.305054)
			(end 0.12065 -0.2794)
			(stroke
				(width 0.1)
				(type default)
			)
			(layer "B.Fab")
		)
		(fp_line
			(start 0.12065 -0.2794)
			(end -0.12065 -0.2794)
			(stroke
				(width 0.1)
				(type default)
			)
			(layer "B.Fab")
		)
		(fp_line
			(start 0.12065 0.2794)
			(end 0.12065 0.3048)
			(stroke
				(width 0.1)
				(type default)
			)
			(layer "B.Fab")
		)
		(fp_line
			(start 0.12065 0.3048)
			(end 0.67945 0.3048)
			(stroke
				(width 0.1)
				(type default)
			)
			(layer "B.Fab")
		)
		(fp_line
			(start 0.67945 -0.305054)
			(end 0.12065 -0.305054)
			(stroke
				(width 0.1)
				(type default)
			)
			(layer "B.Fab")
		)
		(fp_line
			(start 0.67945 0.3048)
			(end 0.67945 -0.305054)
			(stroke
				(width 0.1)
				(type default)
			)
			(layer "B.Fab")
		)
		(pad "1" smd circle
			(at 0.40005 0 180)
			(size 0 0)
			(layers "B.Cu" "B.Mask" "B.Paste")
			(net "P3V3_BIC_USB_HUB")
		)
		(pad "2" smd circle
			(at -0.40005 0 180)
			(size 0 0)
			(layers "B.Cu" "B.Mask" "B.Paste")
			(net "GND")
		)
	)
	(footprint ""
		(layer "B.Cu")
		(at 100.712016 -332.038452)
		(property "Reference" "C2700"
			(at 0 0 0)
			(layer "B.SilkS")
			(hide yes)
			(effects
				(font
					(size 1.27 1.27)
				)
				(justify mirror)
			)
		)
		(property "Value" ""
			(at 0 0 0)
			(layer "B.Fab")
			(effects
				(font
					(size 1.27 1.27)
				)
				(justify mirror)
			)
		)
		(duplicate_pad_numbers_are_jumpers no)
		(fp_line
			(start -0.7874 -0.4064)
			(end -0.7874 0.4064)
			(stroke
				(width 0.1524)
				(type default)
			)
			(layer "B.SilkS")
		)
		(fp_line
			(start -0.7874 0.4064)
			(end 0.7874 0.4064)
			(stroke
				(width 0.1524)
				(type default)
			)
			(layer "B.SilkS")
		)
		(fp_line
			(start 0.7874 -0.4064)
			(end -0.7874 -0.4064)
			(stroke
				(width 0.1524)
				(type default)
			)
			(layer "B.SilkS")
		)
		(fp_line
			(start 0.7874 0.4064)
			(end 0.7874 -0.4064)
			(stroke
				(width 0.1524)
				(type default)
			)
			(layer "B.SilkS")
		)
		(fp_line
			(start -0.67945 -0.3048)
			(end -0.67945 0.3048)
			(stroke
				(width 0.1)
				(type default)
			)
			(layer "B.Fab")
		)
		(fp_line
			(start -0.67945 0.3048)
			(end -0.120396 0.3048)
			(stroke
				(width 0.1)
				(type default)
			)
			(layer "B.Fab")
		)
		(fp_line
			(start -0.12065 -0.3048)
			(end -0.67945 -0.3048)
			(stroke
				(width 0.1)
				(type default)
			)
			(layer "B.Fab")
		)
		(fp_line
			(start -0.12065 -0.2794)
			(end -0.12065 -0.3048)
			(stroke
				(width 0.1)
				(type default)
			)
			(layer "B.Fab")
		)
		(fp_line
			(start -0.120396 0.2794)
			(end 0.12065 0.2794)
			(stroke
				(width 0.1)
				(type default)
			)
			(layer "B.Fab")
		)
		(fp_line
			(start -0.120396 0.3048)
			(end -0.120396 0.2794)
			(stroke
				(width 0.1)
				(type default)
			)
			(layer "B.Fab")
		)
		(fp_line
			(start 0.12065 -0.305054)
			(end 0.12065 -0.2794)
			(stroke
				(width 0.1)
				(type default)
			)
			(layer "B.Fab")
		)
		(fp_line
			(start 0.12065 -0.2794)
			(end -0.12065 -0.2794)
			(stroke
				(width 0.1)
				(type default)
			)
			(layer "B.Fab")
		)
		(fp_line
			(start 0.12065 0.2794)
			(end 0.12065 0.3048)
			(stroke
				(width 0.1)
				(type default)
			)
			(layer "B.Fab")
		)
		(fp_line
			(start 0.12065 0.3048)
			(end 0.67945 0.3048)
			(stroke
				(width 0.1)
				(type default)
			)
			(layer "B.Fab")
		)
		(fp_line
			(start 0.67945 -0.305054)
			(end 0.12065 -0.305054)
			(stroke
				(width 0.1)
				(type default)
			)
			(layer "B.Fab")
		)
		(fp_line
			(start 0.67945 0.3048)
			(end 0.67945 -0.305054)
			(stroke
				(width 0.1)
				(type default)
			)
			(layer "B.Fab")
		)
		(pad "1" smd circle
			(at 0.40005 0 180)
			(size 0 0)
			(layers "B.Cu" "B.Mask" "B.Paste")
			(net "P3V3_CLK_BUFFER_9ZXL0451E_VZX3P3")
		)
		(pad "2" smd circle
			(at -0.40005 0 180)
			(size 0 0)
			(layers "B.Cu" "B.Mask" "B.Paste")
			(net "GND")
		)
	)
	(footprint ""
		(layer "B.Cu")
		(at 8.875268 -277.036276 180)
		(property "Reference" "C4237"
			(at 0 0 0)
			(layer "B.SilkS")
			(hide yes)
			(effects
				(font
					(size 1.27 1.27)
				)
				(justify mirror)
			)
		)
		(property "Value" ""
			(at 0 0 0)
			(layer "B.Fab")
			(effects
				(font
					(size 1.27 1.27)
				)
				(justify mirror)
			)
		)
		(duplicate_pad_numbers_are_jumpers no)
		(fp_line
			(start 0.299974 0.150114)
			(end 0.299974 -0.150114)
			(stroke
				(width 0.1)
				(type default)
			)
			(layer "B.Fab")
		)
		(fp_line
			(start 0.299974 -0.150114)
			(end -0.299974 -0.150114)
			(stroke
				(width 0.1)
				(type default)
			)
			(layer "B.Fab")
		)
		(fp_line
			(start -0.299974 0.150114)
			(end 0.299974 0.150114)
			(stroke
				(width 0.1)
				(type default)
			)
			(layer "B.Fab")
		)
		(fp_line
			(start -0.299974 -0.150114)
			(end -0.299974 0.150114)
			(stroke
				(width 0.1)
				(type default)
			)
			(layer "B.Fab")
		)
		(pad "1" smd rect
			(at 0.2667 0)
			(size 0.3048 0.381)
			(layers "B.Cu" "B.Mask" "B.Paste")
			(net "P1V25_PEX0")
		)
		(pad "2" smd rect
			(at -0.2667 0)
			(size 0.3048 0.381)
			(layers "B.Cu" "B.Mask" "B.Paste")
			(net "GND")
		)
	)
	(footprint ""
		(layer "B.Cu")
		(at 180.50002 -292.099746 90)
		(property "Reference" "C1493"
			(at 0 0 90)
			(layer "B.SilkS")
			(hide yes)
			(effects
				(font
					(size 1.27 1.27)
				)
				(justify mirror)
			)
		)
		(property "Value" ""
			(at 0 0 90)
			(layer "B.Fab")
			(effects
				(font
					(size 1.27 1.27)
				)
				(justify mirror)
			)
		)
		(duplicate_pad_numbers_are_jumpers no)
		(fp_line
			(start 0.299974 -0.150114)
			(end -0.299974 -0.150114)
			(stroke
				(width 0.1)
				(type default)
			)
			(layer "B.Fab")
		)
		(fp_line
			(start -0.299974 -0.150114)
			(end -0.299974 0.150114)
			(stroke
				(width 0.1)
				(type default)
			)
			(layer "B.Fab")
		)
		(fp_line
			(start 0.299974 0.150114)
			(end 0.299974 -0.150114)
			(stroke
				(width 0.1)
				(type default)
			)
			(layer "B.Fab")
		)
		(fp_line
			(start -0.299974 0.150114)
			(end 0.299974 0.150114)
			(stroke
				(width 0.1)
				(type default)
			)
			(layer "B.Fab")
		)
		(pad "1" smd rect
			(at 0.2667 0 270)
			(size 0.3048 0.381)
			(layers "B.Cu" "B.Mask" "B.Paste")
			(net "P0V8_SERDES_VDDA_PEX1")
		)
		(pad "2" smd rect
			(at -0.2667 0 270)
			(size 0.3048 0.381)
			(layers "B.Cu" "B.Mask" "B.Paste")
			(net "GND")
		)
	)
	(footprint ""
		(layer "B.Cu")
		(at 110.82655 -321.36334 -90)
		(property "Reference" "R6452"
			(at 0 0 90)
			(layer "B.SilkS")
			(hide yes)
			(effects
				(font
					(size 1.27 1.27)
				)
				(justify mirror)
			)
		)
		(property "Value" ""
			(at 0 0 90)
			(layer "B.Fab")
			(effects
				(font
					(size 1.27 1.27)
				)
				(justify mirror)
			)
		)
		(duplicate_pad_numbers_are_jumpers no)
		(fp_line
			(start -0.7874 0.4064)
			(end 0.7874 0.4064)
			(stroke
				(width 0.1524)
				(type default)
			)
			(layer "B.SilkS")
		)
		(fp_line
			(start 0.7874 0.4064)
			(end 0.7874 -0.4064)
			(stroke
				(width 0.1524)
				(type default)
			)
			(layer "B.SilkS")
		)
		(fp_line
			(start -0.7874 -0.4064)
			(end -0.7874 0.4064)
			(stroke
				(width 0.1524)
				(type default)
			)
			(layer "B.SilkS")
		)
		(fp_line
			(start 0.7874 -0.4064)
			(end -0.7874 -0.4064)
			(stroke
				(width 0.1524)
				(type default)
			)
			(layer "B.SilkS")
		)
		(fp_line
			(start -0.67945 0.3048)
			(end -0.120396 0.3048)
			(stroke
				(width 0.1)
				(type default)
			)
			(layer "B.Fab")
		)
		(fp_line
			(start -0.120396 0.3048)
			(end -0.120396 0.2794)
			(stroke
				(width 0.1)
				(type default)
			)
			(layer "B.Fab")
		)
		(fp_line
			(start 0.12065 0.3048)
			(end 0.67945 0.3048)
			(stroke
				(width 0.1)
				(type default)
			)
			(layer "B.Fab")
		)
		(fp_line
			(start 0.67945 0.3048)
			(end 0.67945 -0.305054)
			(stroke
				(width 0.1)
				(type default)
			)
			(layer "B.Fab")
		)
		(fp_line
			(start -0.120396 0.2794)
			(end 0.12065 0.2794)
			(stroke
				(width 0.1)
				(type default)
			)
			(layer "B.Fab")
		)
		(fp_line
			(start 0.12065 0.2794)
			(end 0.12065 0.3048)
			(stroke
				(width 0.1)
				(type default)
			)
			(layer "B.Fab")
		)
		(fp_line
			(start -0.12065 -0.2794)
			(end -0.12065 -0.3048)
			(stroke
				(width 0.1)
				(type default)
			)
			(layer "B.Fab")
		)
		(fp_line
			(start 0.12065 -0.2794)
			(end -0.12065 -0.2794)
			(stroke
				(width 0.1)
				(type default)
			)
			(layer "B.Fab")
		)
		(fp_line
			(start -0.67945 -0.3048)
			(end -0.67945 0.3048)
			(stroke
				(width 0.1)
				(type default)
			)
			(layer "B.Fab")
		)
		(fp_line
			(start -0.12065 -0.3048)
			(end -0.67945 -0.3048)
			(stroke
				(width 0.1)
				(type default)
			)
			(layer "B.Fab")
		)
		(fp_line
			(start 0.12065 -0.305054)
			(end 0.12065 -0.2794)
			(stroke
				(width 0.1)
				(type default)
			)
			(layer "B.Fab")
		)
		(fp_line
			(start 0.67945 -0.305054)
			(end 0.12065 -0.305054)
			(stroke
				(width 0.1)
				(type default)
			)
			(layer "B.Fab")
		)
		(pad "1" smd circle
			(at 0.40005 0 90)
			(size 0 0)
			(layers "B.Cu" "B.Mask" "B.Paste")
			(net "P0V8_SERDES_VDDA_PEX0")
		)
		(pad "2" smd circle
			(at -0.40005 0 90)
			(size 0 0)
			(layers "B.Cu" "B.Mask" "B.Paste")
			(net "P0V8_SERDES_VDDA_PEX0_C3")
		)
	)
)
